# T6G (Grand Teton) — schematic netlist excerpt (pin names and nets, part order shuffled) for the footprints in the layout excerpt that follows; sources: Cadence DE-HDL packaged netlist, KiCad conversion of 04192023_DAF0TMB3IC0_F0TG_MB_C_brd_V02_OCP.brd

R5027  Q_RES  4.7K 5% EMPTY  pkg 0402LF  page 28 : A = GND ; B = IRQ_SMI_ACTIVE_N
C408  Q_CAP  22UF 4V 20% X6S  pkg C0402  page 345 : A = P0V9_CPU1_RT_2D ; B = GND

(kicad_pcb
	(version 20260206)
	(generator "pcbnew")
	(generator_version "10.0")
	(general
		(thickness 1.6)
		(legacy_teardrops no)
	)
	(paper "A4")
	(title_block
		(title "04192023_DAF0TMB3IC0_F0TG_MB_C_brd_V02_OCP.brd")
		(comment 1 "Grand Teton / footprints 5856-5857 of 8354")
	)
	(layers
		(0 "F.Cu" signal "TOP")
		(4 "In1.Cu" signal "GND")
		(6 "In2.Cu" signal "IN1")
		(8 "In3.Cu" signal "GND1")
		(10 "In4.Cu" signal "IN2")
		(12 "In5.Cu" signal "GND2")
		(14 "In6.Cu" signal "IN3")
		(16 "In7.Cu" signal "GND3")
		(18 "In8.Cu" signal "VCC")
		(20 "In9.Cu" signal "VCC1")
		(22 "In10.Cu" signal "GND4")
		(24 "In11.Cu" signal "IN4")
		(26 "In12.Cu" signal "GND5")
		(28 "In13.Cu" signal "IN5")
		(30 "In14.Cu" signal "GND6")
		(32 "In15.Cu" signal "IN6")
		(34 "In16.Cu" signal "GND7")
		(2 "B.Cu" signal "BOTTOM")
		(9 "F.Adhes" user "F.Adhesive")
		(11 "B.Adhes" user "B.Adhesive")
		(13 "F.Paste" user "Package Geometry/Pastemask Top")
		(15 "B.Paste" user "Package Geometry/Pastemask Bottom")
		(5 "F.SilkS" user "Ref Des/Silkscreen Top")
		(7 "B.SilkS" user "Ref Des/Silkscreen Bottom")
		(1 "F.Mask" user "Board Geometry/Soldermask Top")
		(3 "B.Mask" user "Board Geometry/Soldermask Bottom")
		(17 "Dwgs.User" user "User.Drawings")
		(19 "Cmts.User" user "User.Comments")
		(21 "Eco1.User" user "User.Eco1")
		(23 "Eco2.User" user "User.Eco2")
		(25 "Edge.Cuts" user "Board Geometry/Outline")
		(27 "Margin" user)
		(31 "F.CrtYd" user "Package Geometry/Place Bound Top")
		(29 "B.CrtYd" user "Package Geometry/Place Bound Bottom")
		(35 "F.Fab" user "Ref Des/Assembly Top")
		(33 "B.Fab" user "Ref Des/Assembly Bottom")
	)
	(footprint ""
		(layer "B.Cu")
		(at 157.81909 -390.560052 90)
		(property "Reference" "C408"
			(at 0 0 90)
			(layer "B.SilkS")
			(hide yes)
			(effects
				(font
					(size 1.27 1.27)
				)
				(justify mirror)
			)
		)
		(property "Value" ""
			(at 0 0 90)
			(layer "B.Fab")
			(effects
				(font
					(size 1.27 1.27)
				)
				(justify mirror)
			)
		)
		(duplicate_pad_numbers_are_jumpers no)
		(fp_line
			(start 0.7874 -0.4064)
			(end -0.7874 -0.4064)
			(stroke
				(width 0.1524)
				(type default)
			)
			(layer "B.SilkS")
		)
		(fp_line
			(start -0.7874 -0.4064)
			(end -0.7874 0.4064)
			(stroke
				(width 0.1524)
				(type default)
			)
			(layer "B.SilkS")
		)
		(fp_line
			(start 0.7874 0.4064)
			(end 0.7874 -0.4064)
			(stroke
				(width 0.1524)
				(type default)
			)
			(layer "B.SilkS")
		)
		(fp_line
			(start -0.7874 0.4064)
			(end 0.7874 0.4064)
			(stroke
				(width 0.1524)
				(type default)
			)
			(layer "B.SilkS")
		)
		(fp_line
			(start 0.67945 -0.305054)
			(end 0.12065 -0.305054)
			(stroke
				(width 0.1)
				(type default)
			)
			(layer "B.Fab")
		)
		(fp_line
			(start 0.12065 -0.305054)
			(end 0.12065 -0.2794)
			(stroke
				(width 0.1)
				(type default)
			)
			(layer "B.Fab")
		)
		(fp_line
			(start -0.12065 -0.3048)
			(end -0.67945 -0.3048)
			(stroke
				(width 0.1)
				(type default)
			)
			(layer "B.Fab")
		)
		(fp_line
			(start -0.67945 -0.3048)
			(end -0.67945 0.3048)
			(stroke
				(width 0.1)
				(type default)
			)
			(layer "B.Fab")
		)
		(fp_line
			(start 0.12065 -0.2794)
			(end -0.12065 -0.2794)
			(stroke
				(width 0.1)
				(type default)
			)
			(layer "B.Fab")
		)
		(fp_line
			(start -0.12065 -0.2794)
			(end -0.12065 -0.3048)
			(stroke
				(width 0.1)
				(type default)
			)
			(layer "B.Fab")
		)
		(fp_line
			(start 0.12065 0.2794)
			(end 0.12065 0.3048)
			(stroke
				(width 0.1)
				(type default)
			)
			(layer "B.Fab")
		)
		(fp_line
			(start -0.120396 0.2794)
			(end 0.12065 0.2794)
			(stroke
				(width 0.1)
				(type default)
			)
			(layer "B.Fab")
		)
		(fp_line
			(start 0.67945 0.3048)
			(end 0.67945 -0.305054)
			(stroke
				(width 0.1)
				(type default)
			)
			(layer "B.Fab")
		)
		(fp_line
			(start 0.12065 0.3048)
			(end 0.67945 0.3048)
			(stroke
				(width 0.1)
				(type default)
			)
			(layer "B.Fab")
		)
		(fp_line
			(start -0.120396 0.3048)
			(end -0.120396 0.2794)
			(stroke
				(width 0.1)
				(type default)
			)
			(layer "B.Fab")
		)
		(fp_line
			(start -0.67945 0.3048)
			(end -0.120396 0.3048)
			(stroke
				(width 0.1)
				(type default)
			)
			(layer "B.Fab")
		)
		(pad "1" smd circle
			(at 0.40005 0 270)
			(size 0 0)
			(layers "B.Cu" "B.Mask" "B.Paste")
			(net "P0V9_CPU1_RT_2D")
		)
		(pad "2" smd circle
			(at -0.40005 0 270)
			(size 0 0)
			(layers "B.Cu" "B.Mask" "B.Paste")
			(net "GND")
		)
	)
	(footprint ""
		(layer "B.Cu")
		(at 402.322538 -322.170552)
		(property "Reference" "R5027"
			(at 0 0 0)
			(layer "B.SilkS")
			(hide yes)
			(effects
				(font
					(size 1.27 1.27)
				)
				(justify mirror)
			)
		)
		(property "Value" ""
			(at 0 0 0)
			(layer "B.Fab")
			(effects
				(font
					(size 1.27 1.27)
				)
				(justify mirror)
			)
		)
		(duplicate_pad_numbers_are_jumpers no)
		(fp_line
			(start -0.7874 -0.4064)
			(end -0.7874 0.4064)
			(stroke
				(width 0.1524)
				(type default)
			)
			(layer "B.SilkS")
		)
		(fp_line
			(start -0.7874 0.4064)
			(end 0.7874 0.4064)
			(stroke
				(width 0.1524)
				(type default)
			)
			(layer "B.SilkS")
		)
		(fp_line
			(start 0.7874 -0.4064)
			(end -0.7874 -0.4064)
			(stroke
				(width 0.1524)
				(type default)
			)
			(layer "B.SilkS")
		)
		(fp_line
			(start 0.7874 0.4064)
			(end 0.7874 -0.4064)
			(stroke
				(width 0.1524)
				(type default)
			)
			(layer "B.SilkS")
		)
		(fp_line
			(start -0.67945 -0.3048)
			(end -0.67945 0.3048)
			(stroke
				(width 0.1)
				(type default)
			)
			(layer "B.Fab")
		)
		(fp_line
			(start -0.67945 0.3048)
			(end -0.120396 0.3048)
			(stroke
				(width 0.1)
				(type default)
			)
			(layer "B.Fab")
		)
		(fp_line
			(start -0.12065 -0.3048)
			(end -0.67945 -0.3048)
			(stroke
				(width 0.1)
				(type default)
			)
			(layer "B.Fab")
		)
		(fp_line
			(start -0.12065 -0.2794)
			(end -0.12065 -0.3048)
			(stroke
				(width 0.1)
				(type default)
			)
			(layer "B.Fab")
		)
		(fp_line
			(start -0.120396 0.2794)
			(end 0.12065 0.2794)
			(stroke
				(width 0.1)
				(type default)
			)
			(layer "B.Fab")
		)
		(fp_line
			(start -0.120396 0.3048)
			(end -0.120396 0.2794)
			(stroke
				(width 0.1)
				(type default)
			)
			(layer "B.Fab")
		)
		(fp_line
			(start 0.12065 -0.305054)
			(end 0.12065 -0.2794)
			(stroke
				(width 0.1)
				(type default)
			)
			(layer "B.Fab")
		)
		(fp_line
			(start 0.12065 -0.2794)
			(end -0.12065 -0.2794)
			(stroke
				(width 0.1)
				(type default)
			)
			(layer "B.Fab")
		)
		(fp_line
			(start 0.12065 0.2794)
			(end 0.12065 0.3048)
			(stroke
				(width 0.1)
				(type default)
			)
			(layer "B.Fab")
		)
		(fp_line
			(start 0.12065 0.3048)
			(end 0.67945 0.3048)
			(stroke
				(width 0.1)
				(type default)
			)
			(layer "B.Fab")
		)
		(fp_line
			(start 0.67945 -0.305054)
			(end 0.12065 -0.305054)
			(stroke
				(width 0.1)
				(type default)
			)
			(layer "B.Fab")
		)
		(fp_line
			(start 0.67945 0.3048)
			(end 0.67945 -0.305054)
			(stroke
				(width 0.1)
				(type default)
			)
			(layer "B.Fab")
		)
		(pad "1" smd circle
			(at 0.40005 0 180)
			(size 0 0)
			(layers "B.Cu" "B.Mask" "B.Paste")
			(net "GND")
		)
		(pad "2" smd circle
			(at -0.40005 0 180)
			(size 0 0)
			(layers "B.Cu" "B.Mask" "B.Paste")
			(net "IRQ_SMI_ACTIVE_N")
		)
	)
)
